# SCM (Grand Teton) — schematic netlist excerpt (pin names and nets, part order shuffled) for the footprints in the layout excerpt that follows; sources: Cadence DE-HDL packaged netlist, KiCad conversion of 12092022_DA0F0TMDCD0_F0T_Management_Board_D_brd_V3_OCP.brd

R577  Q_RES  0 5% CHIP  pkg 0402LF  page 36 : A = FM_SOL_UART_CH_SEL ; B = FM_SOL_UART_CH_SEL_R2
R436  Q_RES  33.2 1% CHIP  pkg 0402LF  page 34 : A = SGPIO_PLD_LD_0 ; B = SGPIO_LD_0
DM3  DUMMY_SYMBOL  BIOS_FLASH MECH  pkg TP30_FOR_BOM  page 59 : \1\ = NC

(kicad_pcb
	(version 20260206)
	(generator "pcbnew")
	(generator_version "10.0")
	(general
		(thickness 1.6)
		(legacy_teardrops no)
	)
	(paper "A4")
	(title_block
		(title "12092022_DA0F0TMDCD0_F0T_Management_Board_D_brd_V3_OCP.brd")
		(comment 1 "Grand Teton / footprints 447-449 of 1440")
	)
	(layers
		(0 "F.Cu" signal "TOP")
		(4 "In1.Cu" signal "GND")
		(6 "In2.Cu" signal "IN1")
		(8 "In3.Cu" signal "GND1")
		(10 "In4.Cu" signal "IN2")
		(12 "In5.Cu" signal "VCC")
		(14 "In6.Cu" signal "VCC1")
		(16 "In7.Cu" signal "IN3")
		(18 "In8.Cu" signal "GND2")
		(20 "In9.Cu" signal "IN4")
		(22 "In10.Cu" signal "GND3")
		(2 "B.Cu" signal "BOTTOM")
		(9 "F.Adhes" user "F.Adhesive")
		(11 "B.Adhes" user "B.Adhesive")
		(13 "F.Paste" user "Package Geometry/Pastemask Top")
		(15 "B.Paste" user "Package Geometry/Pastemask Bottom")
		(5 "F.SilkS" user "Ref Des/Silkscreen Top")
		(7 "B.SilkS" user "Ref Des/Silkscreen Bottom")
		(1 "F.Mask" user "Board Geometry/Soldermask Top")
		(3 "B.Mask" user "Board Geometry/Soldermask Bottom")
		(17 "Dwgs.User" user "User.Drawings")
		(19 "Cmts.User" user "User.Comments")
		(21 "Eco1.User" user "User.Eco1")
		(23 "Eco2.User" user "User.Eco2")
		(25 "Edge.Cuts" user "Board Geometry/Outline")
		(27 "Margin" user)
		(31 "F.CrtYd" user "Package Geometry/Place Bound Top")
		(29 "B.CrtYd" user "Package Geometry/Place Bound Bottom")
		(35 "F.Fab" user "Ref Des/Assembly Top")
		(33 "B.Fab" user "Ref Des/Assembly Bottom")
	)
	(footprint ""
		(layer "F.Cu")
		(at -4.191 -138.303)
		(property "Reference" "DM3"
			(at -0.3937 -0.588518 0)
			(unlocked yes)
			(layer "F.SilkS")
			(effects
				(font
					(size 0.254 0.127)
					(thickness 0.000001)
				)
				(justify left)
			)
		)
		(property "Value" ""
			(at 0 0 0)
			(layer "F.Fab")
			(effects
				(font
					(size 1.27 1.27)
				)
			)
		)
		(duplicate_pad_numbers_are_jumpers no)
		(pad "1" smd circle
			(at 0 0)
			(size 0.762 0.762)
			(layers "F.Cu" "F.Mask" "F.Paste")
			(net "Net_1198")
		)
	)
	(footprint ""
		(layer "F.Cu")
		(at 28.575 -102.743 -90)
		(property "Reference" "R577"
			(at 0 0 270)
			(layer "F.SilkS")
			(hide yes)
			(effects
				(font
					(size 1.27 1.27)
				)
			)
		)
		(property "Value" ""
			(at 0 0 270)
			(layer "F.Fab")
			(effects
				(font
					(size 1.27 1.27)
				)
			)
		)
		(duplicate_pad_numbers_are_jumpers no)
		(fp_line
			(start -0.7874 0.4064)
			(end -0.7874 -0.4064)
			(stroke
				(width 0.1524)
				(type default)
			)
			(layer "F.SilkS")
		)
		(fp_line
			(start 0.7874 0.4064)
			(end -0.7874 0.4064)
			(stroke
				(width 0.1524)
				(type default)
			)
			(layer "F.SilkS")
		)
		(fp_line
			(start -0.7874 -0.4064)
			(end 0.7874 -0.4064)
			(stroke
				(width 0.1524)
				(type default)
			)
			(layer "F.SilkS")
		)
		(fp_line
			(start 0.7874 -0.4064)
			(end 0.7874 0.4064)
			(stroke
				(width 0.1524)
				(type default)
			)
			(layer "F.SilkS")
		)
		(fp_line
			(start -0.67945 0.3048)
			(end -0.67945 -0.305054)
			(stroke
				(width 0.1)
				(type default)
			)
			(layer "F.Fab")
		)
		(fp_line
			(start -0.12065 0.3048)
			(end -0.67945 0.3048)
			(stroke
				(width 0.1)
				(type default)
			)
			(layer "F.Fab")
		)
		(fp_line
			(start 0.120396 0.3048)
			(end 0.120396 0.2794)
			(stroke
				(width 0.1)
				(type default)
			)
			(layer "F.Fab")
		)
		(fp_line
			(start 0.67945 0.3048)
			(end 0.120396 0.3048)
			(stroke
				(width 0.1)
				(type default)
			)
			(layer "F.Fab")
		)
		(fp_line
			(start -0.12065 0.2794)
			(end -0.12065 0.3048)
			(stroke
				(width 0.1)
				(type default)
			)
			(layer "F.Fab")
		)
		(fp_line
			(start 0.120396 0.2794)
			(end -0.12065 0.2794)
			(stroke
				(width 0.1)
				(type default)
			)
			(layer "F.Fab")
		)
		(fp_line
			(start -0.12065 -0.2794)
			(end 0.12065 -0.2794)
			(stroke
				(width 0.1)
				(type default)
			)
			(layer "F.Fab")
		)
		(fp_line
			(start 0.12065 -0.2794)
			(end 0.12065 -0.3048)
			(stroke
				(width 0.1)
				(type default)
			)
			(layer "F.Fab")
		)
		(fp_line
			(start 0.12065 -0.3048)
			(end 0.67945 -0.3048)
			(stroke
				(width 0.1)
				(type default)
			)
			(layer "F.Fab")
		)
		(fp_line
			(start 0.67945 -0.3048)
			(end 0.67945 0.3048)
			(stroke
				(width 0.1)
				(type default)
			)
			(layer "F.Fab")
		)
		(fp_line
			(start -0.67945 -0.305054)
			(end -0.12065 -0.305054)
			(stroke
				(width 0.1)
				(type default)
			)
			(layer "F.Fab")
		)
		(fp_line
			(start -0.12065 -0.305054)
			(end -0.12065 -0.2794)
			(stroke
				(width 0.1)
				(type default)
			)
			(layer "F.Fab")
		)
		(pad "1" smd circle
			(at -0.40005 0 270)
			(size 0 0)
			(layers "F.Cu" "F.Mask" "F.Paste")
			(net "FM_SOL_UART_CH_SEL")
		)
		(pad "2" smd circle
			(at 0.40005 0 270)
			(size 0 0)
			(layers "F.Cu" "F.Mask" "F.Paste")
			(net "FM_SOL_UART_CH_SEL_R2")
		)
	)
	(footprint ""
		(layer "F.Cu")
		(at 16.4846 -83.693 -90)
		(property "Reference" "R436"
			(at 0 0 270)
			(layer "F.SilkS")
			(hide yes)
			(effects
				(font
					(size 1.27 1.27)
				)
			)
		)
		(property "Value" ""
			(at 0 0 270)
			(layer "F.Fab")
			(effects
				(font
					(size 1.27 1.27)
				)
			)
		)
		(duplicate_pad_numbers_are_jumpers no)
		(fp_line
			(start -0.7874 0.4064)
			(end -0.7874 -0.4064)
			(stroke
				(width 0.1524)
				(type default)
			)
			(layer "F.SilkS")
		)
		(fp_line
			(start 0.7874 0.4064)
			(end -0.7874 0.4064)
			(stroke
				(width 0.1524)
				(type default)
			)
			(layer "F.SilkS")
		)
		(fp_line
			(start -0.7874 -0.4064)
			(end 0.7874 -0.4064)
			(stroke
				(width 0.1524)
				(type default)
			)
			(layer "F.SilkS")
		)
		(fp_line
			(start 0.7874 -0.4064)
			(end 0.7874 0.4064)
			(stroke
				(width 0.1524)
				(type default)
			)
			(layer "F.SilkS")
		)
		(fp_line
			(start -0.67945 0.3048)
			(end -0.67945 -0.305054)
			(stroke
				(width 0.1)
				(type default)
			)
			(layer "F.Fab")
		)
		(fp_line
			(start -0.12065 0.3048)
			(end -0.67945 0.3048)
			(stroke
				(width 0.1)
				(type default)
			)
			(layer "F.Fab")
		)
		(fp_line
			(start 0.120396 0.3048)
			(end 0.120396 0.2794)
			(stroke
				(width 0.1)
				(type default)
			)
			(layer "F.Fab")
		)
		(fp_line
			(start 0.67945 0.3048)
			(end 0.120396 0.3048)
			(stroke
				(width 0.1)
				(type default)
			)
			(layer "F.Fab")
		)
		(fp_line
			(start -0.12065 0.2794)
			(end -0.12065 0.3048)
			(stroke
				(width 0.1)
				(type default)
			)
			(layer "F.Fab")
		)
		(fp_line
			(start 0.120396 0.2794)
			(end -0.12065 0.2794)
			(stroke
				(width 0.1)
				(type default)
			)
			(layer "F.Fab")
		)
		(fp_line
			(start -0.12065 -0.2794)
			(end 0.12065 -0.2794)
			(stroke
				(width 0.1)
				(type default)
			)
			(layer "F.Fab")
		)
		(fp_line
			(start 0.12065 -0.2794)
			(end 0.12065 -0.3048)
			(stroke
				(width 0.1)
				(type default)
			)
			(layer "F.Fab")
		)
		(fp_line
			(start 0.12065 -0.3048)
			(end 0.67945 -0.3048)
			(stroke
				(width 0.1)
				(type default)
			)
			(layer "F.Fab")
		)
		(fp_line
			(start 0.67945 -0.3048)
			(end 0.67945 0.3048)
			(stroke
				(width 0.1)
				(type default)
			)
			(layer "F.Fab")
		)
		(fp_line
			(start -0.67945 -0.305054)
			(end -0.12065 -0.305054)
			(stroke
				(width 0.1)
				(type default)
			)
			(layer "F.Fab")
		)
		(fp_line
			(start -0.12065 -0.305054)
			(end -0.12065 -0.2794)
			(stroke
				(width 0.1)
				(type default)
			)
			(layer "F.Fab")
		)
		(pad "1" smd circle
			(at -0.40005 0 270)
			(size 0 0)
			(layers "F.Cu" "F.Mask" "F.Paste")
			(net "SGPIO_PLD_LD_0")
		)
		(pad "2" smd circle
			(at 0.40005 0 270)
			(size 0 0)
			(layers "F.Cu" "F.Mask" "F.Paste")
			(net "SGPIO_LD_0")
		)
	)
)
